(kicad_pcb
	(version 20260206)
	(generator "pcbnew")
	(generator_version "10.0")
	(general
		(thickness 1.6)
		(legacy_teardrops no)
	)
	(paper "A4")
	(title_block
		(title "peb — Lightning_PEB_BRD.brd")
		(comment 1 "Lightning (Wiwynn / Facebook NVMe JBOF) / footprints 408-415 of 2563")
	)
	(layers
		(0 "F.Cu" signal "TOP")
		(4 "In1.Cu" signal "L2GND")
		(6 "In2.Cu" signal "L3")
		(8 "In3.Cu" signal "L4VCC")
		(10 "In4.Cu" signal "L5VCC")
		(12 "In5.Cu" signal "L6")
		(14 "In6.Cu" signal "L7GND")
		(2 "B.Cu" signal "BOTTOM")
		(9 "F.Adhes" user "F.Adhesive")
		(11 "B.Adhes" user "B.Adhesive")
		(13 "F.Paste" user "Package Geometry/Pastemask Top")
		(15 "B.Paste" user "Package Geometry/Pastemask Bottom")
		(5 "F.SilkS" user "Ref Des/Silkscreen Top")
		(7 "B.SilkS" user "Ref Des/Silkscreen Bottom")
		(1 "F.Mask" user "Board Geometry/Soldermask Top")
		(3 "B.Mask" user "Board Geometry/Soldermask Bottom")
		(17 "Dwgs.User" user "User.Drawings")
		(19 "Cmts.User" user "User.Comments")
		(21 "Eco1.User" user "User.Eco1")
		(23 "Eco2.User" user "User.Eco2")
		(25 "Edge.Cuts" user "Board Geometry/Outline")
		(27 "Margin" user)
		(31 "F.CrtYd" user "Package Geometry/Place Bound Top")
		(29 "B.CrtYd" user "Package Geometry/Place Bound Bottom")
		(35 "F.Fab" user "Ref Des/Assembly Top")
		(33 "B.Fab" user "Ref Des/Assembly Bottom")
	)
	(footprint ""
		(layer "F.Cu")
		(at 142.247874 -86.10092 -90)
		(property "Reference" "PC87"
			(at 0 0 270)
			(layer "F.SilkS")
			(hide yes)
			(effects
				(font
					(size 1.27 1.27)
				)
			)
		)
		(property "Value" "SCD01U25V2KX-3GP"
			(at 1.1811 -2.7051 270)
			(unlocked yes)
			(layer "F.Fab")
			(hide yes)
			(effects
				(font
					(size 1.016 1.016)
					(thickness 0.1524)
				)
			)
		)
		(property "Device Type" "C402H22"
			(at 1.1811 -4.2291 270)
			(unlocked yes)
			(layer "F.Fab")
			(hide yes)
			(effects
				(font
					(size 1.016 1.016)
					(thickness 0.1524)
				)
			)
		)
		(duplicate_pad_numbers_are_jumpers no)
		(fp_rect
			(start -0.4318 0.9525)
			(end 0.4318 -0.9525)
			(stroke
				(width 0)
				(type default)
			)
			(fill no)
			(layer "F.CrtYd")
		)
		(fp_rect
			(start -0.4318 0.9525)
			(end 0.4318 -0.9525)
			(stroke
				(width 0)
				(type default)
			)
			(fill no)
			(layer "F.Fab")
		)
		(pad "1" smd custom
			(at 0 -0.4445 270)
			(size 0.1524 0.1524)
			(layers "F.Cu" "F.Mask" "F.Paste")
			(net "P1V8_PWR")
			(options
				(clearance outline)
				(anchor circle)
			)
			(primitives
				(gr_poly
					(pts
						(arc
							(start 0.3048 -0.2032)
							(mid 0.275042 -0.275042)
							(end 0.2032 -0.3048)
						)
						(arc
							(start -0.2032 -0.3048)
							(mid -0.275042 -0.275042)
							(end -0.3048 -0.2032)
						)
						(arc
							(start -0.3048 0.2032)
							(mid -0.275042 0.275042)
							(end -0.2032 0.3048)
						)
						(arc
							(start 0.2032 0.3048)
							(mid 0.275042 0.275042)
							(end 0.3048 0.2032)
						)
					)
					(width 0)
					(fill yes)
				)
			)
		)
		(pad "2" smd custom
			(at 0 0.4445 270)
			(size 0.1524 0.1524)
			(layers "F.Cu" "F.Mask" "F.Paste")
			(net "VR_P1V8_STBY_FB")
			(options
				(clearance outline)
				(anchor circle)
			)
			(primitives
				(gr_poly
					(pts
						(arc
							(start 0.3048 -0.2032)
							(mid 0.275042 -0.275042)
							(end 0.2032 -0.3048)
						)
						(arc
							(start -0.2032 -0.3048)
							(mid -0.275042 -0.275042)
							(end -0.3048 -0.2032)
						)
						(arc
							(start -0.3048 0.2032)
							(mid -0.275042 0.275042)
							(end -0.2032 0.3048)
						)
						(arc
							(start 0.2032 0.3048)
							(mid 0.275042 0.275042)
							(end 0.3048 0.2032)
						)
					)
					(width 0)
					(fill yes)
				)
			)
		)
	)
	(footprint ""
		(layer "F.Cu")
		(at 166.116 -95.6564 90)
		(property "Reference" "R62"
			(at 0 0 90)
			(layer "F.SilkS")
			(hide yes)
			(effects
				(font
					(size 1.27 1.27)
				)
			)
		)
		(property "Value" "10KR2F-2-GP"
			(at 0.064008 -3.993896 90)
			(unlocked yes)
			(layer "F.Fab")
			(hide yes)
			(effects
				(font
					(size 1.016 1.016)
					(thickness 0.1524)
				)
			)
		)
		(property "Device Type" "R402H16"
			(at 0.064008 -5.517896 90)
			(unlocked yes)
			(layer "F.Fab")
			(hide yes)
			(effects
				(font
					(size 1.016 1.016)
					(thickness 0.1524)
				)
			)
		)
		(duplicate_pad_numbers_are_jumpers no)
		(fp_line
			(start 0.508 -0.9398)
			(end -0.508 -0.9398)
			(stroke
				(width 0.1524)
				(type default)
			)
			(layer "F.SilkS")
		)
		(fp_line
			(start -0.508 -0.9398)
			(end -0.508 0.9398)
			(stroke
				(width 0.1524)
				(type default)
			)
			(layer "F.SilkS")
		)
		(fp_rect
			(start -0.508 0.9398)
			(end 0.508 -0.9398)
			(stroke
				(width 0)
				(type default)
			)
			(fill no)
			(layer "F.CrtYd")
		)
		(fp_rect
			(start -0.508 0.9398)
			(end 0.508 -0.9398)
			(stroke
				(width 0)
				(type default)
			)
			(fill no)
			(layer "F.Fab")
		)
		(pad "1" smd custom
			(at 0 -0.4445 90)
			(size 0.1397 0.1397)
			(layers "F.Cu" "F.Mask" "F.Paste")
			(net "GND")
			(options
				(clearance outline)
				(anchor circle)
			)
			(primitives
				(gr_poly
					(pts
						(arc
							(start -0.1778 -0.2794)
							(mid -0.249642 -0.249642)
							(end -0.2794 -0.1778)
						)
						(arc
							(start -0.2794 0.1778)
							(mid -0.249642 0.249642)
							(end -0.1778 0.2794)
						)
						(arc
							(start 0.1778 0.2794)
							(mid 0.249642 0.249642)
							(end 0.2794 0.1778)
						)
						(arc
							(start 0.2794 -0.1778)
							(mid 0.249642 -0.249642)
							(end 0.1778 -0.2794)
						)
					)
					(width 0)
					(fill yes)
				)
			)
		)
		(pad "2" smd custom
			(at 0 0.4445 90)
			(size 0.1397 0.1397)
			(layers "F.Cu" "F.Mask" "F.Paste")
			(net "CLKGEN_OE2")
			(options
				(clearance outline)
				(anchor circle)
			)
			(primitives
				(gr_poly
					(pts
						(arc
							(start -0.1778 -0.2794)
							(mid -0.249642 -0.249642)
							(end -0.2794 -0.1778)
						)
						(arc
							(start -0.2794 0.1778)
							(mid -0.249642 0.249642)
							(end -0.1778 0.2794)
						)
						(arc
							(start 0.1778 0.2794)
							(mid 0.249642 0.249642)
							(end 0.2794 0.1778)
						)
						(arc
							(start 0.2794 -0.1778)
							(mid 0.249642 -0.249642)
							(end 0.1778 -0.2794)
						)
					)
					(width 0)
					(fill yes)
				)
			)
		)
	)
	(footprint ""
		(layer "F.Cu")
		(at 40.554148 -68.890642 90)
		(property "Reference" "PG1"
			(at 0 0 90)
			(layer "F.SilkS")
			(hide yes)
			(effects
				(font
					(size 1.27 1.27)
				)
			)
		)
		(property "Value" "GAP-CLOSE-PWR-3-GP"
			(at 0.0254 -6.5786 90)
			(unlocked yes)
			(layer "F.Fab")
			(hide yes)
			(effects
				(font
					(size 1.016 1.016)
					(thickness 0.1524)
				)
			)
		)
		(property "Device Type" "GAP-CLOSE-PWR-3"
			(at 0.0254 -8.255 90)
			(unlocked yes)
			(layer "F.Fab")
			(hide yes)
			(effects
				(font
					(size 1.016 1.016)
					(thickness 0.1524)
				)
			)
		)
		(duplicate_pad_numbers_are_jumpers no)
		(fp_rect
			(start -0.7112 0.4572)
			(end 0.7112 -0.4572)
			(stroke
				(width 0)
				(type default)
			)
			(fill no)
			(layer "F.CrtYd")
		)
		(fp_poly
			(pts
				(xy -0.7112 -0.4572) (xy 0.7112 -0.4572) (xy 0.7112 0.4572) (xy -0.7112 0.4572)
			)
			(stroke
				(width 0)
				(type default)
			)
			(fill no)
			(layer "F.Fab")
		)
		(pad "1" smd rect
			(at -0.3048 0 90)
			(size 0.6604 0.762)
			(layers "F.Cu" "F.Mask" "F.Paste")
			(net "P5V_STBY")
		)
		(pad "2" smd rect
			(at 0.3048 0 90)
			(size 0.6604 0.762)
			(layers "F.Cu" "F.Mask" "F.Paste")
			(net "P5V_STBY_LR")
		)
	)
	(footprint ""
		(layer "F.Cu")
		(at 16.891 -105.918 90)
		(property "Reference" "PC84"
			(at 0 0 90)
			(layer "F.SilkS")
			(hide yes)
			(effects
				(font
					(size 1.27 1.27)
				)
			)
		)
		(property "Value" "SC820P50V2KX-1GP"
			(at 1.1811 -2.7051 90)
			(unlocked yes)
			(layer "F.Fab")
			(hide yes)
			(effects
				(font
					(size 1.016 1.016)
					(thickness 0.1524)
				)
			)
		)
		(property "Device Type" "C402H22"
			(at 1.1811 -4.2291 90)
			(unlocked yes)
			(layer "F.Fab")
			(hide yes)
			(effects
				(font
					(size 1.016 1.016)
					(thickness 0.1524)
				)
			)
		)
		(duplicate_pad_numbers_are_jumpers no)
		(fp_rect
			(start -0.4318 0.9525)
			(end 0.4318 -0.9525)
			(stroke
				(width 0)
				(type default)
			)
			(fill no)
			(layer "F.CrtYd")
		)
		(fp_rect
			(start -0.4318 0.9525)
			(end 0.4318 -0.9525)
			(stroke
				(width 0)
				(type default)
			)
			(fill no)
			(layer "F.Fab")
		)
		(pad "1" smd custom
			(at 0 -0.4445 90)
			(size 0.1524 0.1524)
			(layers "F.Cu" "F.Mask" "F.Paste")
			(net "VR_P1V26_STBY_SS_C")
			(options
				(clearance outline)
				(anchor circle)
			)
			(primitives
				(gr_poly
					(pts
						(arc
							(start 0.3048 -0.2032)
							(mid 0.275042 -0.275042)
							(end 0.2032 -0.3048)
						)
						(arc
							(start -0.2032 -0.3048)
							(mid -0.275042 -0.275042)
							(end -0.3048 -0.2032)
						)
						(arc
							(start -0.3048 0.2032)
							(mid -0.275042 0.275042)
							(end -0.2032 0.3048)
						)
						(arc
							(start 0.2032 0.3048)
							(mid 0.275042 0.275042)
							(end 0.3048 0.2032)
						)
					)
					(width 0)
					(fill yes)
				)
			)
		)
		(pad "2" smd custom
			(at 0 0.4445 90)
			(size 0.1524 0.1524)
			(layers "F.Cu" "F.Mask" "F.Paste")
			(net "GND")
			(options
				(clearance outline)
				(anchor circle)
			)
			(primitives
				(gr_poly
					(pts
						(arc
							(start 0.3048 -0.2032)
							(mid 0.275042 -0.275042)
							(end 0.2032 -0.3048)
						)
						(arc
							(start -0.2032 -0.3048)
							(mid -0.275042 -0.275042)
							(end -0.3048 -0.2032)
						)
						(arc
							(start -0.3048 0.2032)
							(mid -0.275042 0.275042)
							(end -0.2032 0.3048)
						)
						(arc
							(start 0.2032 0.3048)
							(mid 0.275042 0.275042)
							(end 0.3048 0.2032)
						)
					)
					(width 0)
					(fill yes)
				)
			)
		)
	)
	(footprint ""
		(layer "F.Cu")
		(at 50.673 -191.262)
		(property "Reference" "R889"
			(at 0 0 0)
			(layer "F.SilkS")
			(hide yes)
			(effects
				(font
					(size 1.27 1.27)
				)
			)
		)
		(property "Value" "0R2J-2-GP"
			(at 0.064008 -3.993896 0)
			(unlocked yes)
			(layer "F.Fab")
			(hide yes)
			(effects
				(font
					(size 1.016 1.016)
					(thickness 0.1524)
				)
			)
		)
		(property "Device Type" "R402H16"
			(at 0.064008 -5.517896 0)
			(unlocked yes)
			(layer "F.Fab")
			(hide yes)
			(effects
				(font
					(size 1.016 1.016)
					(thickness 0.1524)
				)
			)
		)
		(duplicate_pad_numbers_are_jumpers no)
		(fp_line
			(start -0.508 -0.9398)
			(end -0.508 0.9398)
			(stroke
				(width 0.1524)
				(type default)
			)
			(layer "F.SilkS")
		)
		(fp_line
			(start 0.508 -0.9398)
			(end -0.508 -0.9398)
			(stroke
				(width 0.1524)
				(type default)
			)
			(layer "F.SilkS")
		)
		(fp_rect
			(start -0.508 0.9398)
			(end 0.508 -0.9398)
			(stroke
				(width 0)
				(type default)
			)
			(fill no)
			(layer "F.CrtYd")
		)
		(fp_rect
			(start -0.508 0.9398)
			(end 0.508 -0.9398)
			(stroke
				(width 0)
				(type default)
			)
			(fill no)
			(layer "F.Fab")
		)
		(pad "1" smd custom
			(at 0 -0.4445)
			(size 0.1397 0.1397)
			(layers "F.Cu" "F.Mask" "F.Paste")
			(net "BMC_I2C7_B_DPB_SDA_R")
			(options
				(clearance outline)
				(anchor circle)
			)
			(primitives
				(gr_poly
					(pts
						(arc
							(start -0.1778 -0.2794)
							(mid -0.249642 -0.249642)
							(end -0.2794 -0.1778)
						)
						(arc
							(start -0.2794 0.1778)
							(mid -0.249642 0.249642)
							(end -0.1778 0.2794)
						)
						(arc
							(start 0.1778 0.2794)
							(mid 0.249642 0.249642)
							(end 0.2794 0.1778)
						)
						(arc
							(start 0.2794 -0.1778)
							(mid 0.249642 -0.249642)
							(end 0.1778 -0.2794)
						)
					)
					(width 0)
					(fill yes)
				)
			)
		)
		(pad "2" smd custom
			(at 0 0.4445)
			(size 0.1397 0.1397)
			(layers "F.Cu" "F.Mask" "F.Paste")
			(net "BMC_I2C7_B_DPB_SDA")
			(options
				(clearance outline)
				(anchor circle)
			)
			(primitives
				(gr_poly
					(pts
						(arc
							(start -0.1778 -0.2794)
							(mid -0.249642 -0.249642)
							(end -0.2794 -0.1778)
						)
						(arc
							(start -0.2794 0.1778)
							(mid -0.249642 0.249642)
							(end -0.1778 0.2794)
						)
						(arc
							(start 0.1778 0.2794)
							(mid 0.249642 0.249642)
							(end 0.2794 0.1778)
						)
						(arc
							(start 0.2794 -0.1778)
							(mid 0.249642 -0.249642)
							(end 0.1778 -0.2794)
						)
					)
					(width 0)
					(fill yes)
				)
			)
		)
	)
	(footprint ""
		(layer "F.Cu")
		(at 59.00801 -212.420454 180)
		(property "Reference" "C360"
			(at 0 0 180)
			(layer "F.SilkS")
			(hide yes)
			(effects
				(font
					(size 1.27 1.27)
				)
			)
		)
		(property "Value" "SCD22U10V2KX-1GP"
			(at 1.1811 -2.7051 180)
			(unlocked yes)
			(layer "F.Fab")
			(hide yes)
			(effects
				(font
					(size 1.016 1.016)
					(thickness 0.1524)
				)
			)
		)
		(property "Device Type" "C402H22"
			(at 1.1811 -4.2291 180)
			(unlocked yes)
			(layer "F.Fab")
			(hide yes)
			(effects
				(font
					(size 1.016 1.016)
					(thickness 0.1524)
				)
			)
		)
		(duplicate_pad_numbers_are_jumpers no)
		(fp_rect
			(start -0.4318 0.9525)
			(end 0.4318 -0.9525)
			(stroke
				(width 0)
				(type default)
			)
			(fill no)
			(layer "F.CrtYd")
		)
		(fp_rect
			(start -0.4318 0.9525)
			(end 0.4318 -0.9525)
			(stroke
				(width 0)
				(type default)
			)
			(fill no)
			(layer "F.Fab")
		)
		(pad "1" smd custom
			(at 0 -0.4445 180)
			(size 0.1524 0.1524)
			(layers "F.Cu" "F.Mask" "F.Paste")
			(net "PCIE_TX_CAP_N72")
			(options
				(clearance outline)
				(anchor circle)
			)
			(primitives
				(gr_poly
					(pts
						(arc
							(start 0.3048 -0.2032)
							(mid 0.275042 -0.275042)
							(end 0.2032 -0.3048)
						)
						(arc
							(start -0.2032 -0.3048)
							(mid -0.275042 -0.275042)
							(end -0.3048 -0.2032)
						)
						(arc
							(start -0.3048 0.2032)
							(mid -0.275042 0.275042)
							(end -0.2032 0.3048)
						)
						(arc
							(start 0.2032 0.3048)
							(mid 0.275042 0.275042)
							(end 0.3048 0.2032)
						)
					)
					(width 0)
					(fill yes)
				)
			)
		)
		(pad "2" smd custom
			(at 0 0.4445 180)
			(size 0.1524 0.1524)
			(layers "F.Cu" "F.Mask" "F.Paste")
			(net "PCIE_TX_N72")
			(options
				(clearance outline)
				(anchor circle)
			)
			(primitives
				(gr_poly
					(pts
						(arc
							(start 0.3048 -0.2032)
							(mid 0.275042 -0.275042)
							(end 0.2032 -0.3048)
						)
						(arc
							(start -0.2032 -0.3048)
							(mid -0.275042 -0.275042)
							(end -0.3048 -0.2032)
						)
						(arc
							(start -0.3048 0.2032)
							(mid -0.275042 0.275042)
							(end -0.2032 0.3048)
						)
						(arc
							(start 0.2032 0.3048)
							(mid 0.275042 0.275042)
							(end 0.3048 0.2032)
						)
					)
					(width 0)
					(fill yes)
				)
			)
		)
	)
	(footprint ""
		(layer "F.Cu")
		(at 219.456 -12.319 -90)
		(property "Reference" "R654"
			(at 0 0 270)
			(layer "F.SilkS")
			(hide yes)
			(effects
				(font
					(size 1.27 1.27)
				)
			)
		)
		(property "Value" "100KR2F-L1-GP"
			(at 0.064008 -3.993896 270)
			(unlocked yes)
			(layer "F.Fab")
			(hide yes)
			(effects
				(font
					(size 1.016 1.016)
					(thickness 0.1524)
				)
			)
		)
		(property "Device Type" "R402H16"
			(at 0.064008 -5.517896 270)
			(unlocked yes)
			(layer "F.Fab")
			(hide yes)
			(effects
				(font
					(size 1.016 1.016)
					(thickness 0.1524)
				)
			)
		)
		(duplicate_pad_numbers_are_jumpers no)
		(fp_line
			(start -0.508 -0.9398)
			(end -0.508 0.9398)
			(stroke
				(width 0.1524)
				(type default)
			)
			(layer "F.SilkS")
		)
		(fp_line
			(start 0.508 -0.9398)
			(end -0.508 -0.9398)
			(stroke
				(width 0.1524)
				(type default)
			)
			(layer "F.SilkS")
		)
		(fp_rect
			(start -0.508 0.9398)
			(end 0.508 -0.9398)
			(stroke
				(width 0)
				(type default)
			)
			(fill no)
			(layer "F.CrtYd")
		)
		(fp_rect
			(start -0.508 0.9398)
			(end 0.508 -0.9398)
			(stroke
				(width 0)
				(type default)
			)
			(fill no)
			(layer "F.Fab")
		)
		(pad "1" smd custom
			(at 0 -0.4445 270)
			(size 0.1397 0.1397)
			(layers "F.Cu" "F.Mask" "F.Paste")
			(net "EEPROM_A0")
			(options
				(clearance outline)
				(anchor circle)
			)
			(primitives
				(gr_poly
					(pts
						(arc
							(start -0.1778 -0.2794)
							(mid -0.249642 -0.249642)
							(end -0.2794 -0.1778)
						)
						(arc
							(start -0.2794 0.1778)
							(mid -0.249642 0.249642)
							(end -0.1778 0.2794)
						)
						(arc
							(start 0.1778 0.2794)
							(mid 0.249642 0.249642)
							(end 0.2794 0.1778)
						)
						(arc
							(start 0.2794 -0.1778)
							(mid 0.249642 -0.249642)
							(end 0.1778 -0.2794)
						)
					)
					(width 0)
					(fill yes)
				)
			)
		)
		(pad "2" smd custom
			(at 0 0.4445 270)
			(size 0.1397 0.1397)
			(layers "F.Cu" "F.Mask" "F.Paste")
			(net "GND")
			(options
				(clearance outline)
				(anchor circle)
			)
			(primitives
				(gr_poly
					(pts
						(arc
							(start -0.1778 -0.2794)
							(mid -0.249642 -0.249642)
							(end -0.2794 -0.1778)
						)
						(arc
							(start -0.2794 0.1778)
							(mid -0.249642 0.249642)
							(end -0.1778 0.2794)
						)
						(arc
							(start 0.1778 0.2794)
							(mid 0.249642 0.249642)
							(end 0.2794 0.1778)
						)
						(arc
							(start 0.2794 -0.1778)
							(mid 0.249642 -0.249642)
							(end 0.1778 -0.2794)
						)
					)
					(width 0)
					(fill yes)
				)
			)
		)
	)
	(footprint ""
		(layer "F.Cu")
		(at 199.99198 -212.420454 180)
		(property "Reference" "C117"
			(at 0 0 180)
			(layer "F.SilkS")
			(hide yes)
			(effects
				(font
					(size 1.27 1.27)
				)
			)
		)
		(property "Value" "SCD22U10V2KX-1GP"
			(at 1.1811 -2.7051 180)
			(unlocked yes)
			(layer "F.Fab")
			(hide yes)
			(effects
				(font
					(size 1.016 1.016)
					(thickness 0.1524)
				)
			)
		)
		(property "Device Type" "C402H22"
			(at 1.1811 -4.2291 180)
			(unlocked yes)
			(layer "F.Fab")
			(hide yes)
			(effects
				(font
					(size 1.016 1.016)
					(thickness 0.1524)
				)
			)
		)
		(duplicate_pad_numbers_are_jumpers no)
		(fp_rect
			(start -0.4318 0.9525)
			(end 0.4318 -0.9525)
			(stroke
				(width 0)
				(type default)
			)
			(fill no)
			(layer "F.CrtYd")
		)
		(fp_rect
			(start -0.4318 0.9525)
			(end 0.4318 -0.9525)
			(stroke
				(width 0)
				(type default)
			)
			(fill no)
			(layer "F.Fab")
		)
		(pad "1" smd custom
			(at 0 -0.4445 180)
			(size 0.1524 0.1524)
			(layers "F.Cu" "F.Mask" "F.Paste")
			(net "PCIE_TX_CAP_P42")
			(options
				(clearance outline)
				(anchor circle)
			)
			(primitives
				(gr_poly
					(pts
						(arc
							(start 0.3048 -0.2032)
							(mid 0.275042 -0.275042)
							(end 0.2032 -0.3048)
						)
						(arc
							(start -0.2032 -0.3048)
							(mid -0.275042 -0.275042)
							(end -0.3048 -0.2032)
						)
						(arc
							(start -0.3048 0.2032)
							(mid -0.275042 0.275042)
							(end -0.2032 0.3048)
						)
						(arc
							(start 0.2032 0.3048)
							(mid 0.275042 0.275042)
							(end 0.3048 0.2032)
						)
					)
					(width 0)
					(fill yes)
				)
			)
		)
		(pad "2" smd custom
			(at 0 0.4445 180)
			(size 0.1524 0.1524)
			(layers "F.Cu" "F.Mask" "F.Paste")
			(net "PCIE_TX_P42")
			(options
				(clearance outline)
				(anchor circle)
			)
			(primitives
				(gr_poly
					(pts
						(arc
							(start 0.3048 -0.2032)
							(mid 0.275042 -0.275042)
							(end 0.2032 -0.3048)
						)
						(arc
							(start -0.2032 -0.3048)
							(mid -0.275042 -0.275042)
							(end -0.3048 -0.2032)
						)
						(arc
							(start -0.3048 0.2032)
							(mid -0.275042 0.275042)
							(end -0.2032 0.3048)
						)
						(arc
							(start 0.2032 0.3048)
							(mid 0.275042 0.275042)
							(end 0.3048 0.2032)
						)
					)
					(width 0)
					(fill yes)
				)
			)
		)
	)
)
